# S9S_MB_2U (Grand Teton) — schematic netlist excerpt (pin names and nets, part order shuffled) for the footprints in the layout excerpt that follows; sources: Cadence DE-HDL packaged netlist, KiCad conversion of 03242023_DA0F0TMBIJ0_F0T_Motherboard_J_brd_V01_OCP.brd

C2342  Q_CAP  1000PF 50V 5% EMPTY  pkg 0402  page 246 : A = HPDB_HSC_PWRGD_ISO ; B = GND

PL13  Q_INDUCTOR4P_14  150NH IND  pkg L_TLM117513Q-151QL_11X7-5XA  page 267
  \1\  = SW_PVCCIN_CPU0_SW2
  \2\  = IND_P0_CPL2
  \3\  = IND_P0_CPL3
  \4\  = PVCCIN_CPU0

(kicad_pcb
	(version 20260206)
	(generator "pcbnew")
	(generator_version "10.0")
	(general
		(thickness 1.6)
		(legacy_teardrops no)
	)
	(paper "A4")
	(title_block
		(title "03242023_DA0F0TMBIJ0_F0T_Motherboard_J_brd_V01_OCP.brd")
		(comment 1 "Grand Teton / footprints 660-662 of 6105")
	)
	(layers
		(0 "F.Cu" signal "TOP")
		(4 "In1.Cu" signal "GND")
		(6 "In2.Cu" signal "IN1")
		(8 "In3.Cu" signal "GND1")
		(10 "In4.Cu" signal "IN2")
		(12 "In5.Cu" signal "GND2")
		(14 "In6.Cu" signal "IN3")
		(16 "In7.Cu" signal "GND3")
		(18 "In8.Cu" signal "VCC")
		(20 "In9.Cu" signal "VCC1")
		(22 "In10.Cu" signal "GND4")
		(24 "In11.Cu" signal "IN4")
		(26 "In12.Cu" signal "GND5")
		(28 "In13.Cu" signal "IN5")
		(30 "In14.Cu" signal "GND6")
		(32 "In15.Cu" signal "IN6")
		(34 "In16.Cu" signal "GND7")
		(2 "B.Cu" signal "BOTTOM")
		(9 "F.Adhes" user "F.Adhesive")
		(11 "B.Adhes" user "B.Adhesive")
		(13 "F.Paste" user "Package Geometry/Pastemask Top")
		(15 "B.Paste" user "Package Geometry/Pastemask Bottom")
		(5 "F.SilkS" user "Ref Des/Silkscreen Top")
		(7 "B.SilkS" user "Ref Des/Silkscreen Bottom")
		(1 "F.Mask" user "Board Geometry/Soldermask Top")
		(3 "B.Mask" user "Board Geometry/Soldermask Bottom")
		(17 "Dwgs.User" user "User.Drawings")
		(19 "Cmts.User" user "User.Comments")
		(21 "Eco1.User" user "User.Eco1")
		(23 "Eco2.User" user "User.Eco2")
		(25 "Edge.Cuts" user "Board Geometry/Outline")
		(27 "Margin" user)
		(31 "F.CrtYd" user "Package Geometry/Place Bound Top")
		(29 "B.CrtYd" user "Package Geometry/Place Bound Bottom")
		(35 "F.Fab" user "Ref Des/Assembly Top")
		(33 "B.Fab" user "Ref Des/Assembly Bottom")
	)
	(footprint ""
		(layer "F.Cu")
		(at 284.599888 -411.29204 -90)
		(property "Reference" "C2342"
			(at 0 0 270)
			(layer "F.SilkS")
			(hide yes)
			(effects
				(font
					(size 1.27 1.27)
				)
			)
		)
		(property "Value" ""
			(at 0 0 270)
			(layer "F.Fab")
			(effects
				(font
					(size 1.27 1.27)
				)
			)
		)
		(duplicate_pad_numbers_are_jumpers no)
		(fp_line
			(start -0.7874 0.4064)
			(end -0.7874 -0.4064)
			(stroke
				(width 0.1524)
				(type default)
			)
			(layer "F.SilkS")
		)
		(fp_line
			(start 0.7874 0.4064)
			(end -0.7874 0.4064)
			(stroke
				(width 0.1524)
				(type default)
			)
			(layer "F.SilkS")
		)
		(fp_line
			(start -0.7874 -0.4064)
			(end 0.7874 -0.4064)
			(stroke
				(width 0.1524)
				(type default)
			)
			(layer "F.SilkS")
		)
		(fp_line
			(start 0.7874 -0.4064)
			(end 0.7874 0.4064)
			(stroke
				(width 0.1524)
				(type default)
			)
			(layer "F.SilkS")
		)
		(fp_line
			(start -0.67945 0.3048)
			(end -0.67945 -0.305054)
			(stroke
				(width 0.1)
				(type default)
			)
			(layer "F.Fab")
		)
		(fp_line
			(start -0.12065 0.3048)
			(end -0.67945 0.3048)
			(stroke
				(width 0.1)
				(type default)
			)
			(layer "F.Fab")
		)
		(fp_line
			(start 0.120396 0.3048)
			(end 0.120396 0.2794)
			(stroke
				(width 0.1)
				(type default)
			)
			(layer "F.Fab")
		)
		(fp_line
			(start 0.67945 0.3048)
			(end 0.120396 0.3048)
			(stroke
				(width 0.1)
				(type default)
			)
			(layer "F.Fab")
		)
		(fp_line
			(start -0.12065 0.2794)
			(end -0.12065 0.3048)
			(stroke
				(width 0.1)
				(type default)
			)
			(layer "F.Fab")
		)
		(fp_line
			(start 0.120396 0.2794)
			(end -0.12065 0.2794)
			(stroke
				(width 0.1)
				(type default)
			)
			(layer "F.Fab")
		)
		(fp_line
			(start -0.12065 -0.2794)
			(end 0.12065 -0.2794)
			(stroke
				(width 0.1)
				(type default)
			)
			(layer "F.Fab")
		)
		(fp_line
			(start 0.12065 -0.2794)
			(end 0.12065 -0.3048)
			(stroke
				(width 0.1)
				(type default)
			)
			(layer "F.Fab")
		)
		(fp_line
			(start 0.12065 -0.3048)
			(end 0.67945 -0.3048)
			(stroke
				(width 0.1)
				(type default)
			)
			(layer "F.Fab")
		)
		(fp_line
			(start 0.67945 -0.3048)
			(end 0.67945 0.3048)
			(stroke
				(width 0.1)
				(type default)
			)
			(layer "F.Fab")
		)
		(fp_line
			(start -0.67945 -0.305054)
			(end -0.12065 -0.305054)
			(stroke
				(width 0.1)
				(type default)
			)
			(layer "F.Fab")
		)
		(fp_line
			(start -0.12065 -0.305054)
			(end -0.12065 -0.2794)
			(stroke
				(width 0.1)
				(type default)
			)
			(layer "F.Fab")
		)
		(pad "1" smd circle
			(at -0.40005 0 270)
			(size 0 0)
			(layers "F.Cu" "F.Mask" "F.Paste")
			(net "HPDB_HSC_PWRGD_ISO")
		)
		(pad "2" smd circle
			(at 0.40005 0 270)
			(size 0 0)
			(layers "F.Cu" "F.Mask" "F.Paste")
			(net "GND")
		)
	)
	(footprint ""
		(layer "F.Cu")
		(at 353.0727 -324.445376)
		(property "Reference" "PL13"
			(at -12.45616 6.763258 0)
			(unlocked yes)
			(layer "F.SilkS")
			(effects
				(font
					(size 0.7874 0.5842)
					(thickness 0.1524)
				)
				(justify left)
			)
		)
		(property "Value" ""
			(at 0 0 0)
			(layer "F.Fab")
			(effects
				(font
					(size 1.27 1.27)
				)
			)
		)
		(duplicate_pad_numbers_are_jumpers no)
		(fp_line
			(start -3.750056 -5.500116)
			(end -2.393442 -5.500116)
			(stroke
				(width 0.1524)
				(type default)
			)
			(layer "F.SilkS")
		)
		(fp_line
			(start -3.750056 5.500116)
			(end -3.750056 -5.500116)
			(stroke
				(width 0.1524)
				(type default)
			)
			(layer "F.SilkS")
		)
		(fp_line
			(start -2.393442 5.500116)
			(end -3.750056 5.500116)
			(stroke
				(width 0.1524)
				(type default)
			)
			(layer "F.SilkS")
		)
		(fp_line
			(start 2.393442 5.500116)
			(end 3.750056 5.500116)
			(stroke
				(width 0.1524)
				(type default)
			)
			(layer "F.SilkS")
		)
		(fp_line
			(start 3.750056 -5.500116)
			(end 2.393442 -5.500116)
			(stroke
				(width 0.1524)
				(type default)
			)
			(layer "F.SilkS")
		)
		(fp_line
			(start 3.750056 -4.449572)
			(end 3.750056 -5.500116)
			(stroke
				(width 0.1524)
				(type default)
			)
			(layer "F.SilkS")
		)
		(fp_line
			(start 3.750056 5.500116)
			(end 3.750056 -3.560572)
			(stroke
				(width 0.1524)
				(type default)
			)
			(layer "F.SilkS")
		)
		(fp_poly
			(pts
				(xy -3.434334 -7.043674) (xy -3.074924 -5.965952) (xy -4.152646 -6.325108)
			)
			(stroke
				(width 0)
				(type default)
			)
			(fill yes)
			(layer "F.SilkS")
		)
		(fp_line
			(start -3.750056 -5.500116)
			(end -3.750056 5.500116)
			(stroke
				(width 0.1)
				(type default)
			)
			(layer "F.Fab")
		)
		(fp_line
			(start -3.750056 5.500116)
			(end 3.750056 5.500116)
			(stroke
				(width 0.1)
				(type default)
			)
			(layer "F.Fab")
		)
		(fp_line
			(start 3.750056 -5.500116)
			(end -3.750056 -5.500116)
			(stroke
				(width 0.1)
				(type default)
			)
			(layer "F.Fab")
		)
		(fp_line
			(start 3.750056 5.500116)
			(end 3.750056 -5.500116)
			(stroke
				(width 0.1)
				(type default)
			)
			(layer "F.Fab")
		)
		(fp_poly
			(pts
				(xy -4.9276 -4.757928) (xy -4.9276 -3.741928) (xy -3.9116 -4.249928)
			)
			(stroke
				(width 0)
				(type default)
			)
			(fill yes)
			(layer "F.Fab")
		)
		(pad "1" smd rect
			(at 0 -4.249928 270)
			(size 2.413 4.5212)
			(layers "F.Cu" "F.Mask" "F.Paste")
			(net "SW_PVCCIN_CPU0_SW2")
		)
		(pad "2" smd rect
			(at 0 -1.175004 270)
			(size 1.3716 4.5212)
			(layers "F.Cu" "F.Mask" "F.Paste")
			(net "IND_P0_CPL2")
		)
		(pad "3" smd rect
			(at 0 1.175004 270)
			(size 1.3716 4.5212)
			(layers "F.Cu" "F.Mask" "F.Paste")
			(net "IND_P0_CPL3")
		)
		(pad "4" smd rect
			(at 0 4.249928 270)
			(size 2.413 4.5212)
			(layers "F.Cu" "F.Mask" "F.Paste")
			(net "PVCCIN_CPU0")
		)
	)
	(footprint ""
		(layer "F.Cu")
		(at 466.24748 -53.449728)
		(property "Reference" ""
			(at 0 0 0)
			(layer "F.SilkS")
			(hide yes)
			(effects
				(font
					(size 1.27 1.27)
				)
			)
		)
		(property "Value" ""
			(at 0 0 0)
			(layer "F.Fab")
			(effects
				(font
					(size 1.27 1.27)
				)
			)
		)
		(duplicate_pad_numbers_are_jumpers no)
		(pad "1" smd circle
			(at 0 0)
			(size 0.9906 0.9906)
			(layers "F.Cu" "F.Mask" "F.Paste")
			(net "Net_295")
		)
		(zone
			(layer "F.Cu")
			(hatch none 0.5)
			(connect_pads
				(clearance 0)
			)
			(min_thickness 0.25)
			(keepout
				(tracks not_allowed)
				(vias allowed)
				(pads allowed)
				(copperpour not_allowed)
				(footprints allowed)
			)
			(placement
				(enabled no)
				(sheetname "")
			)
			(fill
				(thermal_gap 0.5)
				(thermal_bridge_width 0.5)
				(island_removal_mode 0)
			)
			(polygon
				(pts
					(arc
						(start 467.87308 -53.449728)
						(mid 464.62188 -53.449728)
						(end 467.87308 -53.449728)
					)
				)
			)
		)
	)
)
